# TIMECARD (Time Appliance Project (Time Card)) — schematic netlist excerpt (pin names and nets, part order shuffled) for the footprints in the layout excerpt that follows; sources: Cadence DE-HDL packaged netlist, KiCad conversion of R4006-B0001-02_R01.brd

ME12  MEC_MTH8  pkg MTH125C236N_V8  page 34
  \1\  = SG
  \2\  = SG
  \3\  = SG
  \4\  = SG
  \5\  = SG
  \6\  = SG
  \7\  = SG
  \8\  = SG

(kicad_pcb
	(version 20260206)
	(generator "pcbnew")
	(generator_version "10.0")
	(general
		(thickness 1.6)
		(legacy_teardrops no)
	)
	(paper "A4")
	(title_block
		(title "timecard-production-celestica-r4006 — R4006-B0001-02_R01.brd")
		(comment 1 "Time Appliance Project (Time Card) / footprints 131-131 of 1113")
	)
	(layers
		(0 "F.Cu" signal "TOP")
		(4 "In1.Cu" signal "L02_GND1")
		(6 "In2.Cu" signal "L03_SIG1")
		(8 "In3.Cu" signal "L04_GND2")
		(10 "In4.Cu" signal "L05_VCC1")
		(12 "In5.Cu" signal "L06_VCC2")
		(14 "In6.Cu" signal "L07_GND3")
		(16 "In7.Cu" signal "L08_SIG2")
		(18 "In8.Cu" signal "L09_GND4")
		(2 "B.Cu" signal "BOTTOM")
		(9 "F.Adhes" user "F.Adhesive")
		(11 "B.Adhes" user "B.Adhesive")
		(13 "F.Paste" user "Package Geometry/Pastemask Top")
		(15 "B.Paste" user "Package Geometry/Pastemask Bottom")
		(5 "F.SilkS" user "Ref Des/Silkscreen Top")
		(7 "B.SilkS" user "Ref Des/Silkscreen Bottom")
		(1 "F.Mask" user "Board Geometry/Soldermask Top")
		(3 "B.Mask" user "Board Geometry/Soldermask Bottom")
		(17 "Dwgs.User" user "User.Drawings")
		(19 "Cmts.User" user "User.Comments")
		(21 "Eco1.User" user "User.Eco1")
		(23 "Eco2.User" user "User.Eco2")
		(25 "Edge.Cuts" user "Board Geometry/Outline")
		(27 "Margin" user)
		(31 "F.CrtYd" user "Package Geometry/Place Bound Top")
		(29 "B.CrtYd" user "Package Geometry/Place Bound Bottom")
		(35 "F.Fab" user "Ref Des/Assembly Top")
		(33 "B.Fab" user "Ref Des/Assembly Bottom")
	)
	(footprint ""
		(layer "F.Cu")
		(at 162.569906 -16.599916)
		(property "Reference" "ME12"
			(at 0.371094 -4.188714 0)
			(unlocked yes)
			(layer "F.SilkS")
			(effects
				(font
					(size 0.7874 0.5842)
					(thickness 0.1524)
				)
			)
		)
		(property "Value" ""
			(at 0 0 0)
			(layer "F.Fab")
			(effects
				(font
					(size 1.27 1.27)
				)
			)
		)
		(property "Device Type" "MEC_MTH8-MTH125C236N_V8-MTH125A"
			(at 0 5.08127 0)
			(unlocked yes)
			(layer "F.Fab")
			(hide yes)
			(effects
				(font
					(size 0.7874 0.5842)
					(thickness 0.1524)
				)
			)
		)
		(duplicate_pad_numbers_are_jumpers no)
		(fp_poly
			(pts
				(arc
					(start 3.5052 0)
					(mid -3.5052 0)
					(end 3.5052 0)
				)
			)
			(stroke
				(width 0)
				(type default)
			)
			(fill no)
			(layer "B.CrtYd")
		)
		(fp_poly
			(pts
				(arc
					(start 3.5052 0)
					(mid -3.5052 0)
					(end 3.5052 0)
				)
			)
			(stroke
				(width 0)
				(type default)
			)
			(fill no)
			(layer "F.CrtYd")
		)
		(fp_circle
			(center 0 0)
			(end 2.9972 0)
			(stroke
				(width 0.1)
				(type default)
			)
			(fill no)
			(layer "B.Fab")
		)
		(fp_circle
			(center 0 0)
			(end 2.9972 0)
			(stroke
				(width 0.1)
				(type default)
			)
			(fill no)
			(layer "F.Fab")
		)
		(pad "" np_thru_hole circle
			(at 0 0)
			(size 2.921 2.921)
			(drill 3.175)
			(layers "*.Cu" "*.Mask")
			(padstack
				(mode front_inner_back)
				(layer "Inner"
					(shape circle)
					(size 2.921 2.921)
					(clearance 0.4445)
				)
				(layer "B.Cu"
					(shape circle)
					(size 2.921 2.921)
				)
			)
		)
		(pad "1" thru_hole circle
			(at 0 -2.4511)
			(size 0.6096 0.6096)
			(drill 0.3048)
			(layers "*.Cu" "*.Mask")
			(remove_unused_layers no)
			(net "SG")
			(padstack
				(mode front_inner_back)
				(layer "Inner"
					(shape circle)
					(size 0.6096 0.6096)
					(clearance 0.1143)
				)
				(layer "B.Cu"
					(shape circle)
					(size 0.6096 0.6096)
				)
			)
		)
		(pad "2" thru_hole circle
			(at 1.733296 -1.733296)
			(size 0.6096 0.6096)
			(drill 0.3048)
			(layers "*.Cu" "*.Mask")
			(remove_unused_layers no)
			(net "SG")
			(padstack
				(mode front_inner_back)
				(layer "Inner"
					(shape circle)
					(size 0.6096 0.6096)
					(clearance 0.1143)
				)
				(layer "B.Cu"
					(shape circle)
					(size 0.6096 0.6096)
				)
			)
		)
		(pad "3" thru_hole circle
			(at 2.4511 0)
			(size 0.6096 0.6096)
			(drill 0.3048)
			(layers "*.Cu" "*.Mask")
			(remove_unused_layers no)
			(net "SG")
			(padstack
				(mode front_inner_back)
				(layer "Inner"
					(shape circle)
					(size 0.6096 0.6096)
					(clearance 0.1143)
				)
				(layer "B.Cu"
					(shape circle)
					(size 0.6096 0.6096)
				)
			)
		)
		(pad "4" thru_hole circle
			(at 1.733296 1.733296)
			(size 0.6096 0.6096)
			(drill 0.3048)
			(layers "*.Cu" "*.Mask")
			(remove_unused_layers no)
			(net "SG")
			(padstack
				(mode front_inner_back)
				(layer "Inner"
					(shape circle)
					(size 0.6096 0.6096)
					(clearance 0.1143)
				)
				(layer "B.Cu"
					(shape circle)
					(size 0.6096 0.6096)
				)
			)
		)
		(pad "5" thru_hole circle
			(at 0 2.4511)
			(size 0.6096 0.6096)
			(drill 0.3048)
			(layers "*.Cu" "*.Mask")
			(remove_unused_layers no)
			(net "SG")
			(padstack
				(mode front_inner_back)
				(layer "Inner"
					(shape circle)
					(size 0.6096 0.6096)
					(clearance 0.1143)
				)
				(layer "B.Cu"
					(shape circle)
					(size 0.6096 0.6096)
				)
			)
		)
		(pad "6" thru_hole circle
			(at -1.733296 1.733296)
			(size 0.6096 0.6096)
			(drill 0.3048)
			(layers "*.Cu" "*.Mask")
			(remove_unused_layers no)
			(net "SG")
			(padstack
				(mode front_inner_back)
				(layer "Inner"
					(shape circle)
					(size 0.6096 0.6096)
					(clearance 0.1143)
				)
				(layer "B.Cu"
					(shape circle)
					(size 0.6096 0.6096)
				)
			)
		)
		(pad "7" thru_hole circle
			(at -2.4511 0)
			(size 0.6096 0.6096)
			(drill 0.3048)
			(layers "*.Cu" "*.Mask")
			(remove_unused_layers no)
			(net "SG")
			(padstack
				(mode front_inner_back)
				(layer "Inner"
					(shape circle)
					(size 0.6096 0.6096)
					(clearance 0.1143)
				)
				(layer "B.Cu"
					(shape circle)
					(size 0.6096 0.6096)
				)
			)
		)
		(pad "8" thru_hole circle
			(at -1.733296 -1.733296)
			(size 0.6096 0.6096)
			(drill 0.3048)
			(layers "*.Cu" "*.Mask")
			(remove_unused_layers no)
			(net "SG")
			(padstack
				(mode front_inner_back)
				(layer "Inner"
					(shape circle)
					(size 0.6096 0.6096)
					(clearance 0.1143)
				)
				(layer "B.Cu"
					(shape circle)
					(size 0.6096 0.6096)
				)
			)
		)
		(zone
			(layers "F.Cu" "B.Cu" "In1.Cu" "In2.Cu" "In3.Cu" "In4.Cu" "In5.Cu" "In6.Cu"
				"In7.Cu" "In8.Cu"
			)
			(hatch none 0.5)
			(connect_pads
				(clearance 0)
			)
			(min_thickness 0.25)
			(keepout
				(tracks not_allowed)
				(vias allowed)
				(pads allowed)
				(copperpour not_allowed)
				(footprints allowed)
			)
			(placement
				(enabled no)
				(sheetname "")
			)
			(fill
				(thermal_gap 0.5)
				(thermal_bridge_width 0.5)
				(island_removal_mode 0)
			)
			(polygon
				(pts
					(arc
						(start 164.462206 -16.599916)
						(mid 160.677606 -16.599916)
						(end 164.462206 -16.599916)
					)
				)
			)
		)
	)
)
